# S9S_MB_2U (Grand Teton) — schematic netlist excerpt (pin names and nets, part order shuffled) for the footprints in the layout excerpt that follows; sources: Cadence DE-HDL packaged netlist, KiCad conversion of 03242023_DA0F0TMBIJ0_F0T_Motherboard_J_brd_V01_OCP.brd

U256  74LVC2G17GW  IC  pkg SOT363  page 149
  A0  = RST_PERST_SWB_R_N
  GND  = GND
  A1  = FM_SWB_PWR_EN_R
  B1  = FM_SWB_PWR_EN_R1_BUF
  VCC  = P3V3_AUX
  B0  = RST_PERST_2_SWB_BUF_R_N

PR701  Q_RES  0 5% CHIP  pkg 0402LF  page 289 : A = P5V ; B = PVCCFA_EHV_FIVRA_CPU1_PVCC1

(kicad_pcb
	(version 20260206)
	(generator "pcbnew")
	(generator_version "10.0")
	(general
		(thickness 1.6)
		(legacy_teardrops no)
	)
	(paper "A4")
	(title_block
		(title "03242023_DA0F0TMBIJ0_F0T_Motherboard_J_brd_V01_OCP.brd")
		(comment 1 "Grand Teton / footprints 1447-1448 of 6105")
	)
	(layers
		(0 "F.Cu" signal "TOP")
		(4 "In1.Cu" signal "GND")
		(6 "In2.Cu" signal "IN1")
		(8 "In3.Cu" signal "GND1")
		(10 "In4.Cu" signal "IN2")
		(12 "In5.Cu" signal "GND2")
		(14 "In6.Cu" signal "IN3")
		(16 "In7.Cu" signal "GND3")
		(18 "In8.Cu" signal "VCC")
		(20 "In9.Cu" signal "VCC1")
		(22 "In10.Cu" signal "GND4")
		(24 "In11.Cu" signal "IN4")
		(26 "In12.Cu" signal "GND5")
		(28 "In13.Cu" signal "IN5")
		(30 "In14.Cu" signal "GND6")
		(32 "In15.Cu" signal "IN6")
		(34 "In16.Cu" signal "GND7")
		(2 "B.Cu" signal "BOTTOM")
		(9 "F.Adhes" user "F.Adhesive")
		(11 "B.Adhes" user "B.Adhesive")
		(13 "F.Paste" user "Package Geometry/Pastemask Top")
		(15 "B.Paste" user "Package Geometry/Pastemask Bottom")
		(5 "F.SilkS" user "Ref Des/Silkscreen Top")
		(7 "B.SilkS" user "Ref Des/Silkscreen Bottom")
		(1 "F.Mask" user "Board Geometry/Soldermask Top")
		(3 "B.Mask" user "Board Geometry/Soldermask Bottom")
		(17 "Dwgs.User" user "User.Drawings")
		(19 "Cmts.User" user "User.Comments")
		(21 "Eco1.User" user "User.Eco1")
		(23 "Eco2.User" user "User.Eco2")
		(25 "Edge.Cuts" user "Board Geometry/Outline")
		(27 "Margin" user)
		(31 "F.CrtYd" user "Package Geometry/Place Bound Top")
		(29 "B.CrtYd" user "Package Geometry/Place Bound Bottom")
		(35 "F.Fab" user "Ref Des/Assembly Top")
		(33 "B.Fab" user "Ref Des/Assembly Bottom")
	)
	(footprint ""
		(layer "F.Cu")
		(at 26.97988 -430.875948)
		(property "Reference" "U256"
			(at -1.9558 -1.97739 0)
			(unlocked yes)
			(layer "F.SilkS")
			(effects
				(font
					(size 0.7874 0.5842)
					(thickness 0.1524)
				)
				(justify left)
			)
		)
		(property "Value" ""
			(at 0 0 0)
			(layer "F.Fab")
			(effects
				(font
					(size 1.27 1.27)
				)
			)
		)
		(duplicate_pad_numbers_are_jumpers no)
		(fp_line
			(start -1.3462 -1.100074)
			(end -0.670052 -1.100074)
			(stroke
				(width 0.1524)
				(type default)
			)
			(layer "F.SilkS")
		)
		(fp_line
			(start -1.3462 1.100074)
			(end -1.3462 -1.100074)
			(stroke
				(width 0.1524)
				(type default)
			)
			(layer "F.SilkS")
		)
		(fp_line
			(start -0.670052 -1.100074)
			(end 0 -0.381)
			(stroke
				(width 0.1524)
				(type default)
			)
			(layer "F.SilkS")
		)
		(fp_line
			(start 0 -0.381)
			(end 0.670052 -1.100074)
			(stroke
				(width 0.1524)
				(type default)
			)
			(layer "F.SilkS")
		)
		(fp_line
			(start 0.670052 -1.100074)
			(end 1.3462 -1.100074)
			(stroke
				(width 0.1524)
				(type default)
			)
			(layer "F.SilkS")
		)
		(fp_line
			(start 1.3462 -1.100074)
			(end 1.3462 1.100074)
			(stroke
				(width 0.1524)
				(type default)
			)
			(layer "F.SilkS")
		)
		(fp_line
			(start 1.3462 1.100074)
			(end -1.3462 1.100074)
			(stroke
				(width 0.1524)
				(type default)
			)
			(layer "F.SilkS")
		)
		(fp_poly
			(pts
				(xy -2.01676 -0.685546) (xy -2.77876 -0.304546) (xy -2.77876 -1.066546)
			)
			(stroke
				(width 0)
				(type default)
			)
			(fill yes)
			(layer "F.SilkS")
		)
		(fp_line
			(start -1.100074 -0.8001)
			(end -0.670052 -0.8001)
			(stroke
				(width 0.1)
				(type default)
			)
			(layer "F.Fab")
		)
		(fp_line
			(start -1.100074 0.8001)
			(end -1.100074 -0.8001)
			(stroke
				(width 0.1)
				(type default)
			)
			(layer "F.Fab")
		)
		(fp_line
			(start -0.670052 -1.100074)
			(end 0.670052 -1.100074)
			(stroke
				(width 0.1)
				(type default)
			)
			(layer "F.Fab")
		)
		(fp_line
			(start -0.670052 -0.8001)
			(end -0.670052 -1.100074)
			(stroke
				(width 0.1)
				(type default)
			)
			(layer "F.Fab")
		)
		(fp_line
			(start -0.670052 0.8001)
			(end -1.100074 0.8001)
			(stroke
				(width 0.1)
				(type default)
			)
			(layer "F.Fab")
		)
		(fp_line
			(start -0.670052 0.8001)
			(end -0.670052 -0.8001)
			(stroke
				(width 0.1)
				(type default)
			)
			(layer "F.Fab")
		)
		(fp_line
			(start -0.670052 1.100074)
			(end -0.670052 0.8001)
			(stroke
				(width 0.1)
				(type default)
			)
			(layer "F.Fab")
		)
		(fp_line
			(start 0.670052 -1.100074)
			(end 0.670052 -0.8001)
			(stroke
				(width 0.1)
				(type default)
			)
			(layer "F.Fab")
		)
		(fp_line
			(start 0.670052 -0.8001)
			(end 0.670052 0.8001)
			(stroke
				(width 0.1)
				(type default)
			)
			(layer "F.Fab")
		)
		(fp_line
			(start 0.670052 -0.8001)
			(end 1.100074 -0.8001)
			(stroke
				(width 0.1)
				(type default)
			)
			(layer "F.Fab")
		)
		(fp_line
			(start 0.670052 0.8001)
			(end 0.670052 1.100074)
			(stroke
				(width 0.1)
				(type default)
			)
			(layer "F.Fab")
		)
		(fp_line
			(start 0.670052 1.100074)
			(end -0.670052 1.100074)
			(stroke
				(width 0.1)
				(type default)
			)
			(layer "F.Fab")
		)
		(fp_line
			(start 1.100074 -0.8001)
			(end 1.100074 0.8001)
			(stroke
				(width 0.1)
				(type default)
			)
			(layer "F.Fab")
		)
		(fp_line
			(start 1.100074 0.8001)
			(end 0.670052 0.8001)
			(stroke
				(width 0.1)
				(type default)
			)
			(layer "F.Fab")
		)
		(fp_poly
			(pts
				(xy -1.524 -0.649986) (xy -2.286 -1.030986) (xy -2.286 -0.268986)
			)
			(stroke
				(width 0)
				(type default)
			)
			(fill yes)
			(layer "F.Fab")
		)
		(pad "1" smd rect
			(at -0.94996 -0.649986 270)
			(size 0.4064 0.508)
			(layers "F.Cu" "F.Mask" "F.Paste")
			(net "RST_PERST_SWB_R_N")
		)
		(pad "2" smd rect
			(at -0.94996 0 270)
			(size 0.4064 0.508)
			(layers "F.Cu" "F.Mask" "F.Paste")
			(net "GND")
		)
		(pad "3" smd rect
			(at -0.94996 0.649986 270)
			(size 0.4064 0.508)
			(layers "F.Cu" "F.Mask" "F.Paste")
			(net "FM_SWB_PWR_EN_R")
		)
		(pad "4" smd rect
			(at 0.94996 0.649986 270)
			(size 0.4064 0.508)
			(layers "F.Cu" "F.Mask" "F.Paste")
			(net "FM_SWB_PWR_EN_R1_BUF")
		)
		(pad "5" smd rect
			(at 0.94996 0 270)
			(size 0.4064 0.508)
			(layers "F.Cu" "F.Mask" "F.Paste")
			(net "P3V3_AUX")
		)
		(pad "6" smd rect
			(at 0.94996 -0.649986 270)
			(size 0.4064 0.508)
			(layers "F.Cu" "F.Mask" "F.Paste")
			(net "RST_PERST_2_SWB_BUF_R_N")
		)
	)
	(footprint ""
		(layer "F.Cu")
		(at 167.064944 -354.6602)
		(property "Reference" "PR701"
			(at 0 0 0)
			(layer "F.SilkS")
			(hide yes)
			(effects
				(font
					(size 1.27 1.27)
				)
			)
		)
		(property "Value" ""
			(at 0 0 0)
			(layer "F.Fab")
			(effects
				(font
					(size 1.27 1.27)
				)
			)
		)
		(duplicate_pad_numbers_are_jumpers no)
		(fp_line
			(start -0.7874 -0.4064)
			(end 0.7874 -0.4064)
			(stroke
				(width 0.1524)
				(type default)
			)
			(layer "F.SilkS")
		)
		(fp_line
			(start -0.7874 0.4064)
			(end -0.7874 -0.4064)
			(stroke
				(width 0.1524)
				(type default)
			)
			(layer "F.SilkS")
		)
		(fp_line
			(start 0.7874 -0.4064)
			(end 0.7874 0.4064)
			(stroke
				(width 0.1524)
				(type default)
			)
			(layer "F.SilkS")
		)
		(fp_line
			(start 0.7874 0.4064)
			(end -0.7874 0.4064)
			(stroke
				(width 0.1524)
				(type default)
			)
			(layer "F.SilkS")
		)
		(fp_line
			(start -0.67945 -0.305054)
			(end -0.12065 -0.305054)
			(stroke
				(width 0.1)
				(type default)
			)
			(layer "F.Fab")
		)
		(fp_line
			(start -0.67945 0.3048)
			(end -0.67945 -0.305054)
			(stroke
				(width 0.1)
				(type default)
			)
			(layer "F.Fab")
		)
		(fp_line
			(start -0.12065 -0.305054)
			(end -0.12065 -0.2794)
			(stroke
				(width 0.1)
				(type default)
			)
			(layer "F.Fab")
		)
		(fp_line
			(start -0.12065 -0.2794)
			(end 0.12065 -0.2794)
			(stroke
				(width 0.1)
				(type default)
			)
			(layer "F.Fab")
		)
		(fp_line
			(start -0.12065 0.2794)
			(end -0.12065 0.3048)
			(stroke
				(width 0.1)
				(type default)
			)
			(layer "F.Fab")
		)
		(fp_line
			(start -0.12065 0.3048)
			(end -0.67945 0.3048)
			(stroke
				(width 0.1)
				(type default)
			)
			(layer "F.Fab")
		)
		(fp_line
			(start 0.120396 0.2794)
			(end -0.12065 0.2794)
			(stroke
				(width 0.1)
				(type default)
			)
			(layer "F.Fab")
		)
		(fp_line
			(start 0.120396 0.3048)
			(end 0.120396 0.2794)
			(stroke
				(width 0.1)
				(type default)
			)
			(layer "F.Fab")
		)
		(fp_line
			(start 0.12065 -0.3048)
			(end 0.67945 -0.3048)
			(stroke
				(width 0.1)
				(type default)
			)
			(layer "F.Fab")
		)
		(fp_line
			(start 0.12065 -0.2794)
			(end 0.12065 -0.3048)
			(stroke
				(width 0.1)
				(type default)
			)
			(layer "F.Fab")
		)
		(fp_line
			(start 0.67945 -0.3048)
			(end 0.67945 0.3048)
			(stroke
				(width 0.1)
				(type default)
			)
			(layer "F.Fab")
		)
		(fp_line
			(start 0.67945 0.3048)
			(end 0.120396 0.3048)
			(stroke
				(width 0.1)
				(type default)
			)
			(layer "F.Fab")
		)
		(pad "1" smd circle
			(at -0.40005 0)
			(size 0 0)
			(layers "F.Cu" "F.Mask" "F.Paste")
			(net "P5V")
		)
		(pad "2" smd circle
			(at 0.40005 0)
			(size 0 0)
			(layers "F.Cu" "F.Mask" "F.Paste")
			(net "PVCCFA_EHV_FIVRA_CPU1_PVCC1")
		)
	)
)
